#ISCELL
  mstr_misc dns *
  *
#ISCELL
  pure_quanta quanta_title_block_c *
  *
#ISCELL
  standard offpage *
  page120_i11
#ISCELL
  standard offpage *
  page120_i12
#ISCELL
  standard offpage *
  page120_i14
#ISCELL
  standard offpage *
  page120_i15
#ISCELL
  standard offpage *
  page120_i16
#ISCELL
  standard offpage *
  page120_i17
#CELL
  pure_quanta q_res *
  page120_i27
#CELL
  pure_quanta q_res *
  page120_i28
#CELL
  pure_quanta q_res *
  page120_i29
#CELL
  pure_quanta q_res *
  page120_i30
#CELL
  pure_quanta q_res *
  page120_i31
#CELL
  pure_quanta q_res *
  page120_i32
#ISCELL
  standard offpage *
  page120_i35
#ISCELL
  standard offpage *
  page120_i36
#ISCELL
  standard offpage *
  page120_i37
#ISCELL
  standard offpage *
  page120_i38
#ISCELL
  standard offpage *
  page120_i39
#ISCELL
  standard offpage *
  page120_i40
#ISCELL
  logical_power universal_power *
  page120_i41
#CELL
  pure_quanta q_res *
  page120_i42
#CELL
  pure_quanta q_res *
  page120_i43
#CELL
  pure_quanta q_res *
  page120_i44
#CELL
  pure_quanta q_res *
  page120_i45
#CELL
  pure_quanta q_res *
  page120_i46
#CELL
  pure_quanta q_res *
  page120_i48
#ISCELL
  logical_power universal_gnd *
  page120_i55
#ISCELL
  standard offpage *
  page120_i57
#ISCELL
  standard offpage *
  page120_i58
#CELL
  pure_quanta q_res *
  page120_i61
#CELL
  pure_quanta q_res *
  page120_i62
#ISCELL
  logical_power universal_gnd *
  page120_i63
#ISCELL
  standard offpage *
  page120_i64
#ISCELL
  standard offpage *
  page120_i65
#CELL
  pure_quanta q_res *
  page120_i66
#CELL
  pure_quanta q_res *
  page120_i67
#ISCELL
  logical_power universal_power *
  page120_i8
